(kicad_pcb
	(version 20260206)
	(generator "pcbnew")
	(generator_version "10.0")
	(general
		(thickness 1.6)
		(legacy_teardrops no)
	)
	(paper "A4")
	(title_block
		(title "03242023_DA0F0TMBIJ0_F0T_Motherboard_J_brd_V01_OCP.brd")
		(comment 1 "Grand Teton / footprint 37 of 6105 (J7), pads 1-112 of 291")
	)
	(layers
		(0 "F.Cu" signal "TOP")
		(4 "In1.Cu" signal "GND")
		(6 "In2.Cu" signal "IN1")
		(8 "In3.Cu" signal "GND1")
		(10 "In4.Cu" signal "IN2")
		(12 "In5.Cu" signal "GND2")
		(14 "In6.Cu" signal "IN3")
		(16 "In7.Cu" signal "GND3")
		(18 "In8.Cu" signal "VCC")
		(20 "In9.Cu" signal "VCC1")
		(22 "In10.Cu" signal "GND4")
		(24 "In11.Cu" signal "IN4")
		(26 "In12.Cu" signal "GND5")
		(28 "In13.Cu" signal "IN5")
		(30 "In14.Cu" signal "GND6")
		(32 "In15.Cu" signal "IN6")
		(34 "In16.Cu" signal "GND7")
		(2 "B.Cu" signal "BOTTOM")
		(9 "F.Adhes" user "F.Adhesive")
		(11 "B.Adhes" user "B.Adhesive")
		(13 "F.Paste" user "Package Geometry/Pastemask Top")
		(15 "B.Paste" user "Package Geometry/Pastemask Bottom")
		(5 "F.SilkS" user "Ref Des/Silkscreen Top")
		(7 "B.SilkS" user "Ref Des/Silkscreen Bottom")
		(1 "F.Mask" user "Board Geometry/Soldermask Top")
		(3 "B.Mask" user "Board Geometry/Soldermask Bottom")
		(17 "Dwgs.User" user "User.Drawings")
		(19 "Cmts.User" user "User.Comments")
		(21 "Eco1.User" user "User.Eco1")
		(23 "Eco2.User" user "User.Eco2")
		(25 "Edge.Cuts" user "Board Geometry/Outline")
		(27 "Margin" user)
		(31 "F.CrtYd" user "Package Geometry/Place Bound Top")
		(29 "B.CrtYd" user "Package Geometry/Place Bound Bottom")
		(35 "F.Fab" user "Ref Des/Assembly Top")
		(33 "B.Fab" user "Ref Des/Assembly Bottom")
	)
	(footprint ""
		(layer "F.Cu")
		(at 258.130548 -258.091686)
		(property "Reference" "J7"
			(at -3.683 -81.702148 0)
			(unlocked yes)
			(layer "F.SilkS")
			(effects
				(font
					(size 0.7874 0.5842)
					(thickness 0.1524)
				)
				(justify left)
			)
		)
		(property "Value" ""
			(at 0 0 0)
			(layer "F.Fab")
			(effects
				(font
					(size 1.27 1.27)
				)
			)
		)
		(duplicate_pad_numbers_are_jumpers no)
		(pad "1" smd rect
			(at -2.050034 -63.324994 270)
			(size 0.519938 1.4986)
			(layers "F.Cu" "F.Mask" "F.Paste")
			(net "P12V_S3_AUX_CPU0_NVDIMM")
		)
		(pad "2" smd rect
			(at -2.050034 -62.47511 270)
			(size 0.519938 1.4986)
			(layers "F.Cu" "F.Mask" "F.Paste")
			(net "TP_CHD_CPU0_DIMM1_FRU_0")
		)
		(pad "3" smd rect
			(at -2.050034 -61.624972 270)
			(size 0.519938 1.4986)
			(layers "F.Cu" "F.Mask" "F.Paste")
			(net "P3V3_AUX")
		)
		(pad "4" smd rect
			(at -2.050034 -60.775088 270)
			(size 0.519938 1.4986)
			(layers "F.Cu" "F.Mask" "F.Paste")
			(net "I3C_SPD_DDRABCD_CPU0_LVC1_SCL_6")
		)
		(pad "5" smd rect
			(at -2.050034 -59.92495 270)
			(size 0.519938 1.4986)
			(layers "F.Cu" "F.Mask" "F.Paste")
			(net "I3C_SPD_DDRABCD_CPU0_LVC1_SDA")
		)
		(pad "6" smd rect
			(at -2.050034 -59.075066 270)
			(size 0.519938 1.4986)
			(layers "F.Cu" "F.Mask" "F.Paste")
			(net "GND")
		)
		(pad "7" smd rect
			(at -2.050034 -58.224928 270)
			(size 0.519938 1.4986)
			(layers "F.Cu" "F.Mask" "F.Paste")
			(net "M_D_CPU0_SA_DQ<0>")
		)
		(pad "8" smd rect
			(at -2.050034 -57.375044 270)
			(size 0.519938 1.4986)
			(layers "F.Cu" "F.Mask" "F.Paste")
			(net "GND")
		)
		(pad "9" smd rect
			(at -2.050034 -56.524906 270)
			(size 0.519938 1.4986)
			(layers "F.Cu" "F.Mask" "F.Paste")
			(net "M_D_CPU0_SA_DQ<1>")
		)
		(pad "10" smd rect
			(at -2.050034 -55.675022 270)
			(size 0.519938 1.4986)
			(layers "F.Cu" "F.Mask" "F.Paste")
			(net "GND")
		)
		(pad "11" smd rect
			(at -2.050034 -54.824884 270)
			(size 0.519938 1.4986)
			(layers "F.Cu" "F.Mask" "F.Paste")
			(net "M_D_CPU0_SA_DQS_DP<0>")
		)
		(pad "12" smd rect
			(at -2.050034 -53.975 270)
			(size 0.519938 1.4986)
			(layers "F.Cu" "F.Mask" "F.Paste")
			(net "M_D_CPU0_SA_DQS_DN<0>")
		)
		(pad "13" smd rect
			(at -2.050034 -53.125116 270)
			(size 0.519938 1.4986)
			(layers "F.Cu" "F.Mask" "F.Paste")
			(net "GND")
		)
		(pad "14" smd rect
			(at -2.050034 -52.274978 270)
			(size 0.519938 1.4986)
			(layers "F.Cu" "F.Mask" "F.Paste")
			(net "M_D_CPU0_SA_DQ<4>")
		)
		(pad "15" smd rect
			(at -2.050034 -51.425094 270)
			(size 0.519938 1.4986)
			(layers "F.Cu" "F.Mask" "F.Paste")
			(net "GND")
		)
		(pad "16" smd rect
			(at -2.050034 -50.574956 270)
			(size 0.519938 1.4986)
			(layers "F.Cu" "F.Mask" "F.Paste")
			(net "M_D_CPU0_SA_DQ<5>")
		)
		(pad "17" smd rect
			(at -2.050034 -49.725072 270)
			(size 0.519938 1.4986)
			(layers "F.Cu" "F.Mask" "F.Paste")
			(net "GND")
		)
		(pad "18" smd rect
			(at -2.050034 -48.874934 270)
			(size 0.519938 1.4986)
			(layers "F.Cu" "F.Mask" "F.Paste")
			(net "M_D_CPU0_SA_DQ<8>")
		)
		(pad "19" smd rect
			(at -2.050034 -48.02505 270)
			(size 0.519938 1.4986)
			(layers "F.Cu" "F.Mask" "F.Paste")
			(net "GND")
		)
		(pad "20" smd rect
			(at -2.050034 -47.174912 270)
			(size 0.519938 1.4986)
			(layers "F.Cu" "F.Mask" "F.Paste")
			(net "M_D_CPU0_SA_DQ<9>")
		)
		(pad "21" smd rect
			(at -2.050034 -46.325028 270)
			(size 0.519938 1.4986)
			(layers "F.Cu" "F.Mask" "F.Paste")
			(net "GND")
		)
		(pad "22" smd rect
			(at -2.050034 -45.47489 270)
			(size 0.519938 1.4986)
			(layers "F.Cu" "F.Mask" "F.Paste")
			(net "M_D_CPU0_SA_DQS_DP<1>")
		)
		(pad "23" smd rect
			(at -2.050034 -44.625006 270)
			(size 0.519938 1.4986)
			(layers "F.Cu" "F.Mask" "F.Paste")
			(net "M_D_CPU0_SA_DQS_DN<1>")
		)
		(pad "24" smd rect
			(at -2.050034 -43.775122 270)
			(size 0.519938 1.4986)
			(layers "F.Cu" "F.Mask" "F.Paste")
			(net "GND")
		)
		(pad "25" smd rect
			(at -2.050034 -42.924984 270)
			(size 0.519938 1.4986)
			(layers "F.Cu" "F.Mask" "F.Paste")
			(net "M_D_CPU0_SA_DQ<12>")
		)
		(pad "26" smd rect
			(at -2.050034 -42.0751 270)
			(size 0.519938 1.4986)
			(layers "F.Cu" "F.Mask" "F.Paste")
			(net "GND")
		)
		(pad "27" smd rect
			(at -2.050034 -41.224962 270)
			(size 0.519938 1.4986)
			(layers "F.Cu" "F.Mask" "F.Paste")
			(net "M_D_CPU0_SA_DQ<13>")
		)
		(pad "28" smd rect
			(at -2.050034 -40.375078 270)
			(size 0.519938 1.4986)
			(layers "F.Cu" "F.Mask" "F.Paste")
			(net "GND")
		)
		(pad "29" smd rect
			(at -2.050034 -39.52494 270)
			(size 0.519938 1.4986)
			(layers "F.Cu" "F.Mask" "F.Paste")
			(net "M_D_CPU0_SA_DQ<16>")
		)
		(pad "30" smd rect
			(at -2.050034 -38.675056 270)
			(size 0.519938 1.4986)
			(layers "F.Cu" "F.Mask" "F.Paste")
			(net "GND")
		)
		(pad "31" smd rect
			(at -2.050034 -37.824918 270)
			(size 0.519938 1.4986)
			(layers "F.Cu" "F.Mask" "F.Paste")
			(net "M_D_CPU0_SA_DQ<17>")
		)
		(pad "32" smd rect
			(at -2.050034 -36.975034 270)
			(size 0.519938 1.4986)
			(layers "F.Cu" "F.Mask" "F.Paste")
			(net "GND")
		)
		(pad "33" smd rect
			(at -2.050034 -36.124896 270)
			(size 0.519938 1.4986)
			(layers "F.Cu" "F.Mask" "F.Paste")
			(net "M_D_CPU0_SA_DQS_DP<2>")
		)
		(pad "34" smd rect
			(at -2.050034 -35.275012 270)
			(size 0.519938 1.4986)
			(layers "F.Cu" "F.Mask" "F.Paste")
			(net "M_D_CPU0_SA_DQS_DN<2>")
		)
		(pad "35" smd rect
			(at -2.050034 -34.425128 270)
			(size 0.519938 1.4986)
			(layers "F.Cu" "F.Mask" "F.Paste")
			(net "GND")
		)
		(pad "36" smd rect
			(at -2.050034 -33.57499 270)
			(size 0.519938 1.4986)
			(layers "F.Cu" "F.Mask" "F.Paste")
			(net "M_D_CPU0_SA_DQ<20>")
		)
		(pad "37" smd rect
			(at -2.050034 -32.725106 270)
			(size 0.519938 1.4986)
			(layers "F.Cu" "F.Mask" "F.Paste")
			(net "GND")
		)
		(pad "38" smd rect
			(at -2.050034 -31.874968 270)
			(size 0.519938 1.4986)
			(layers "F.Cu" "F.Mask" "F.Paste")
			(net "M_D_CPU0_SA_DQ<21>")
		)
		(pad "39" smd rect
			(at -2.050034 -31.025084 270)
			(size 0.519938 1.4986)
			(layers "F.Cu" "F.Mask" "F.Paste")
			(net "GND")
		)
		(pad "40" smd rect
			(at -2.050034 -30.174946 270)
			(size 0.519938 1.4986)
			(layers "F.Cu" "F.Mask" "F.Paste")
			(net "M_D_CPU0_SA_DQ<24>")
		)
		(pad "41" smd rect
			(at -2.050034 -29.325062 270)
			(size 0.519938 1.4986)
			(layers "F.Cu" "F.Mask" "F.Paste")
			(net "GND")
		)
		(pad "42" smd rect
			(at -2.050034 -28.474924 270)
			(size 0.519938 1.4986)
			(layers "F.Cu" "F.Mask" "F.Paste")
			(net "M_D_CPU0_SA_DQ<25>")
		)
		(pad "43" smd rect
			(at -2.050034 -27.62504 270)
			(size 0.519938 1.4986)
			(layers "F.Cu" "F.Mask" "F.Paste")
			(net "GND")
		)
		(pad "44" smd rect
			(at -2.050034 -26.774902 270)
			(size 0.519938 1.4986)
			(layers "F.Cu" "F.Mask" "F.Paste")
			(net "M_D_CPU0_SA_DQS_DP<3>")
		)
		(pad "45" smd rect
			(at -2.050034 -25.925018 270)
			(size 0.519938 1.4986)
			(layers "F.Cu" "F.Mask" "F.Paste")
			(net "M_D_CPU0_SA_DQS_DN<3>")
		)
		(pad "46" smd rect
			(at -2.050034 -25.07488 270)
			(size 0.519938 1.4986)
			(layers "F.Cu" "F.Mask" "F.Paste")
			(net "GND")
		)
		(pad "47" smd rect
			(at -2.050034 -24.224996 270)
			(size 0.519938 1.4986)
			(layers "F.Cu" "F.Mask" "F.Paste")
			(net "M_D_CPU0_SA_DQ<28>")
		)
		(pad "48" smd rect
			(at -2.050034 -23.375112 270)
			(size 0.519938 1.4986)
			(layers "F.Cu" "F.Mask" "F.Paste")
			(net "GND")
		)
		(pad "49" smd rect
			(at -2.050034 -22.524974 270)
			(size 0.519938 1.4986)
			(layers "F.Cu" "F.Mask" "F.Paste")
			(net "M_D_CPU0_SA_DQ<29>")
		)
		(pad "50" smd rect
			(at -2.050034 -21.67509 270)
			(size 0.519938 1.4986)
			(layers "F.Cu" "F.Mask" "F.Paste")
			(net "GND")
		)
		(pad "51" smd rect
			(at -2.050034 -20.824952 270)
			(size 0.519938 1.4986)
			(layers "F.Cu" "F.Mask" "F.Paste")
			(net "M_D_CPU0_SA_CB<0>")
		)
		(pad "52" smd rect
			(at -2.050034 -19.975068 270)
			(size 0.519938 1.4986)
			(layers "F.Cu" "F.Mask" "F.Paste")
			(net "GND")
		)
		(pad "53" smd rect
			(at -2.050034 -19.12493 270)
			(size 0.519938 1.4986)
			(layers "F.Cu" "F.Mask" "F.Paste")
			(net "M_D_CPU0_SA_CB<1>")
		)
		(pad "54" smd rect
			(at -2.050034 -18.275046 270)
			(size 0.519938 1.4986)
			(layers "F.Cu" "F.Mask" "F.Paste")
			(net "GND")
		)
		(pad "55" smd rect
			(at -2.050034 -17.424908 270)
			(size 0.519938 1.4986)
			(layers "F.Cu" "F.Mask" "F.Paste")
			(net "M_D_CPU0_SA_DQS_DP<4>")
		)
		(pad "56" smd rect
			(at -2.050034 -16.575024 270)
			(size 0.519938 1.4986)
			(layers "F.Cu" "F.Mask" "F.Paste")
			(net "M_D_CPU0_SA_DQS_DN<4>")
		)
		(pad "57" smd rect
			(at -2.050034 -15.724886 270)
			(size 0.519938 1.4986)
			(layers "F.Cu" "F.Mask" "F.Paste")
			(net "GND")
		)
		(pad "58" smd rect
			(at -2.050034 -14.875002 270)
			(size 0.519938 1.4986)
			(layers "F.Cu" "F.Mask" "F.Paste")
			(net "M_D_CPU0_SA_CB<4>")
		)
		(pad "59" smd rect
			(at -2.050034 -14.025118 270)
			(size 0.519938 1.4986)
			(layers "F.Cu" "F.Mask" "F.Paste")
			(net "GND")
		)
		(pad "60" smd rect
			(at -2.050034 -13.17498 270)
			(size 0.519938 1.4986)
			(layers "F.Cu" "F.Mask" "F.Paste")
			(net "M_D_CPU0_SA_CB<5>")
		)
		(pad "61" smd rect
			(at -2.050034 -12.325096 270)
			(size 0.519938 1.4986)
			(layers "F.Cu" "F.Mask" "F.Paste")
			(net "GND")
		)
		(pad "62" smd rect
			(at -2.050034 -11.474958 270)
			(size 0.519938 1.4986)
			(layers "F.Cu" "F.Mask" "F.Paste")
			(net "M_D_CPU0_ALERT_N")
		)
		(pad "63" smd rect
			(at -2.050034 -10.625074 270)
			(size 0.519938 1.4986)
			(layers "F.Cu" "F.Mask" "F.Paste")
			(net "GND")
		)
		(pad "64" smd rect
			(at -2.050034 -9.774936 270)
			(size 0.519938 1.4986)
			(layers "F.Cu" "F.Mask" "F.Paste")
			(net "M_D_CPU0_SA_CS_N<0>")
		)
		(pad "65" smd rect
			(at -2.050034 -8.925052 270)
			(size 0.519938 1.4986)
			(layers "F.Cu" "F.Mask" "F.Paste")
			(net "GND")
		)
		(pad "66" smd rect
			(at -2.050034 -8.074914 270)
			(size 0.519938 1.4986)
			(layers "F.Cu" "F.Mask" "F.Paste")
			(net "M_D_CPU0_SA_CA<0>")
		)
		(pad "67" smd rect
			(at -2.050034 -7.22503 270)
			(size 0.519938 1.4986)
			(layers "F.Cu" "F.Mask" "F.Paste")
			(net "GND")
		)
		(pad "68" smd rect
			(at -2.050034 -6.374892 270)
			(size 0.519938 1.4986)
			(layers "F.Cu" "F.Mask" "F.Paste")
			(net "M_D_CPU0_SA_CA<2>")
		)
		(pad "69" smd rect
			(at -2.050034 -5.525008 270)
			(size 0.519938 1.4986)
			(layers "F.Cu" "F.Mask" "F.Paste")
			(net "GND")
		)
		(pad "70" smd rect
			(at -2.050034 -4.675124 270)
			(size 0.519938 1.4986)
			(layers "F.Cu" "F.Mask" "F.Paste")
			(net "M_D_CPU0_SA_CA<4>")
		)
		(pad "71" smd rect
			(at -2.050034 -3.824986 270)
			(size 0.519938 1.4986)
			(layers "F.Cu" "F.Mask" "F.Paste")
			(net "GND")
		)
		(pad "72" smd rect
			(at -2.050034 -2.975102 270)
			(size 0.519938 1.4986)
			(layers "F.Cu" "F.Mask" "F.Paste")
			(net "M_D_CPU0_SA_CA<6>")
		)
		(pad "73" smd rect
			(at -2.050034 -2.124964 270)
			(size 0.519938 1.4986)
			(layers "F.Cu" "F.Mask" "F.Paste")
			(net "GND")
		)
		(pad "74" smd rect
			(at -2.050034 -1.27508 270)
			(size 0.519938 1.4986)
			(layers "F.Cu" "F.Mask" "F.Paste")
			(net "M_D_CPU0_SA_PAR")
		)
		(pad "75" smd rect
			(at -2.050034 -0.424942 270)
			(size 0.519938 1.4986)
			(layers "F.Cu" "F.Mask" "F.Paste")
			(net "GND")
		)
		(pad "76" smd rect
			(at -2.050034 5.525008 270)
			(size 0.519938 1.4986)
			(layers "F.Cu" "F.Mask" "F.Paste")
			(net "M_D_CPU0_SB_CA<0>")
		)
		(pad "77" smd rect
			(at -2.050034 6.374892 270)
			(size 0.519938 1.4986)
			(layers "F.Cu" "F.Mask" "F.Paste")
			(net "GND")
		)
		(pad "78" smd rect
			(at -2.050034 7.22503 270)
			(size 0.519938 1.4986)
			(layers "F.Cu" "F.Mask" "F.Paste")
			(net "M_D_CPU0_SB_CA<2>")
		)
		(pad "79" smd rect
			(at -2.050034 8.074914 270)
			(size 0.519938 1.4986)
			(layers "F.Cu" "F.Mask" "F.Paste")
			(net "GND")
		)
		(pad "80" smd rect
			(at -2.050034 8.925052 270)
			(size 0.519938 1.4986)
			(layers "F.Cu" "F.Mask" "F.Paste")
			(net "M_D_CPU0_SB_CA<4>")
		)
		(pad "81" smd rect
			(at -2.050034 9.774936 270)
			(size 0.519938 1.4986)
			(layers "F.Cu" "F.Mask" "F.Paste")
			(net "GND")
		)
		(pad "82" smd rect
			(at -2.050034 10.625074 270)
			(size 0.519938 1.4986)
			(layers "F.Cu" "F.Mask" "F.Paste")
			(net "M_D_CPU0_SB_CA<6>")
		)
		(pad "83" smd rect
			(at -2.050034 11.474958 270)
			(size 0.519938 1.4986)
			(layers "F.Cu" "F.Mask" "F.Paste")
			(net "GND")
		)
		(pad "84" smd rect
			(at -2.050034 12.325096 270)
			(size 0.519938 1.4986)
			(layers "F.Cu" "F.Mask" "F.Paste")
			(net "M_D_CPU0_SB_CS_N<0>")
		)
		(pad "85" smd rect
			(at -2.050034 13.17498 270)
			(size 0.519938 1.4986)
			(layers "F.Cu" "F.Mask" "F.Paste")
			(net "GND")
		)
		(pad "86" smd rect
			(at -2.050034 14.025118 270)
			(size 0.519938 1.4986)
			(layers "F.Cu" "F.Mask" "F.Paste")
			(net "M_D_CPU0_SA_RSP<0>")
		)
		(pad "87" smd rect
			(at -2.050034 14.875002 270)
			(size 0.519938 1.4986)
			(layers "F.Cu" "F.Mask" "F.Paste")
			(net "M_D_CPU0_SB_RSP<0>")
		)
		(pad "88" smd rect
			(at -2.050034 15.724886 270)
			(size 0.519938 1.4986)
			(layers "F.Cu" "F.Mask" "F.Paste")
			(net "GND")
		)
		(pad "89" smd rect
			(at -2.050034 16.575024 270)
			(size 0.519938 1.4986)
			(layers "F.Cu" "F.Mask" "F.Paste")
			(net "M_D_CPU0_SB_CB<4>")
		)
		(pad "90" smd rect
			(at -2.050034 17.424908 270)
			(size 0.519938 1.4986)
			(layers "F.Cu" "F.Mask" "F.Paste")
			(net "GND")
		)
		(pad "91" smd rect
			(at -2.050034 18.275046 270)
			(size 0.519938 1.4986)
			(layers "F.Cu" "F.Mask" "F.Paste")
			(net "M_D_CPU0_SB_CB<5>")
		)
		(pad "92" smd rect
			(at -2.050034 19.12493 270)
			(size 0.519938 1.4986)
			(layers "F.Cu" "F.Mask" "F.Paste")
			(net "GND")
		)
		(pad "93" smd rect
			(at -2.050034 19.975068 270)
			(size 0.519938 1.4986)
			(layers "F.Cu" "F.Mask" "F.Paste")
			(net "M_D_CPU0_SB_DQS_DP<9>")
		)
		(pad "94" smd rect
			(at -2.050034 20.824952 270)
			(size 0.519938 1.4986)
			(layers "F.Cu" "F.Mask" "F.Paste")
			(net "M_D_CPU0_SB_DQS_DN<9>")
		)
		(pad "95" smd rect
			(at -2.050034 21.67509 270)
			(size 0.519938 1.4986)
			(layers "F.Cu" "F.Mask" "F.Paste")
			(net "GND")
		)
		(pad "96" smd rect
			(at -2.050034 22.524974 270)
			(size 0.519938 1.4986)
			(layers "F.Cu" "F.Mask" "F.Paste")
			(net "M_D_CPU0_SB_CB<0>")
		)
		(pad "97" smd rect
			(at -2.050034 23.375112 270)
			(size 0.519938 1.4986)
			(layers "F.Cu" "F.Mask" "F.Paste")
			(net "GND")
		)
		(pad "98" smd rect
			(at -2.050034 24.224996 270)
			(size 0.519938 1.4986)
			(layers "F.Cu" "F.Mask" "F.Paste")
			(net "M_D_CPU0_SB_CB<1>")
		)
		(pad "99" smd rect
			(at -2.050034 25.07488 270)
			(size 0.519938 1.4986)
			(layers "F.Cu" "F.Mask" "F.Paste")
			(net "GND")
		)
		(pad "100" smd rect
			(at -2.050034 25.925018 270)
			(size 0.519938 1.4986)
			(layers "F.Cu" "F.Mask" "F.Paste")
			(net "M_D_CPU0_SB_DQ<0>")
		)
		(pad "101" smd rect
			(at -2.050034 26.774902 270)
			(size 0.519938 1.4986)
			(layers "F.Cu" "F.Mask" "F.Paste")
			(net "GND")
		)
		(pad "102" smd rect
			(at -2.050034 27.62504 270)
			(size 0.519938 1.4986)
			(layers "F.Cu" "F.Mask" "F.Paste")
			(net "M_D_CPU0_SB_DQ<1>")
		)
		(pad "103" smd rect
			(at -2.050034 28.474924 270)
			(size 0.519938 1.4986)
			(layers "F.Cu" "F.Mask" "F.Paste")
			(net "GND")
		)
		(pad "104" smd rect
			(at -2.050034 29.325062 270)
			(size 0.519938 1.4986)
			(layers "F.Cu" "F.Mask" "F.Paste")
			(net "M_D_CPU0_SB_DQS_DP<0>")
		)
		(pad "105" smd rect
			(at -2.050034 30.174946 270)
			(size 0.519938 1.4986)
			(layers "F.Cu" "F.Mask" "F.Paste")
			(net "M_D_CPU0_SB_DQS_DN<0>")
		)
		(pad "106" smd rect
			(at -2.050034 31.025084 270)
			(size 0.519938 1.4986)
			(layers "F.Cu" "F.Mask" "F.Paste")
			(net "GND")
		)
		(pad "107" smd rect
			(at -2.050034 31.874968 270)
			(size 0.519938 1.4986)
			(layers "F.Cu" "F.Mask" "F.Paste")
			(net "M_D_CPU0_SB_DQ<4>")
		)
		(pad "108" smd rect
			(at -2.050034 32.725106 270)
			(size 0.519938 1.4986)
			(layers "F.Cu" "F.Mask" "F.Paste")
			(net "GND")
		)
		(pad "109" smd rect
			(at -2.050034 33.57499 270)
			(size 0.519938 1.4986)
			(layers "F.Cu" "F.Mask" "F.Paste")
			(net "M_D_CPU0_SB_DQ<5>")
		)
		(pad "110" smd rect
			(at -2.050034 34.425128 270)
			(size 0.519938 1.4986)
			(layers "F.Cu" "F.Mask" "F.Paste")
			(net "GND")
		)
		(pad "111" smd rect
			(at -2.050034 35.275012 270)
			(size 0.519938 1.4986)
			(layers "F.Cu" "F.Mask" "F.Paste")
			(net "M_D_CPU0_SB_DQ<8>")
		)
		(pad "112" smd rect
			(at -2.050034 36.124896 270)
			(size 0.519938 1.4986)
			(layers "F.Cu" "F.Mask" "F.Paste")
			(net "GND")
		)
	)
)
